# BASEBOARD_FAB2 (Tioga Pass) — schematic netlist excerpt (pin names and nets, part order shuffled) for the footprints in the layout excerpt that follows; sources: Cadence DE-HDL packaged netlist, KiCad conversion of Wiwynn_Tioga_Pass_MB.brd

C1W20  CAP  0.22UF 16V 10% X7R  pkg 0402  page 151 : A = BMC_M_CLK ; B = GND
R25W42  120R2F-GP  1%  pkg RCL_GP  page 151 : \1\ = BMC_M_A4 ; \2\ = P1V2_AUX_BMC
C3L13  CAP  10UF 16V 10% X6S  pkg 0805  page 219 : A = VR_FET_SW_P12V_STBY_PVDDQ_DEF ; B = GND

(kicad_pcb
	(version 20260206)
	(generator "pcbnew")
	(generator_version "10.0")
	(general
		(thickness 1.6)
		(legacy_teardrops no)
	)
	(paper "A4")
	(title_block
		(title "Wiwynn_Tioga_Pass_MB.brd")
		(comment 1 "Tioga Pass / footprints 3828-3830 of 4770")
	)
	(layers
		(0 "F.Cu" signal "TOP")
		(4 "In1.Cu" signal "L2GND")
		(6 "In2.Cu" signal "L3")
		(8 "In3.Cu" signal "L4GND")
		(10 "In4.Cu" signal "L5")
		(12 "In5.Cu" signal "L6GND")
		(14 "In6.Cu" signal "L7VCC")
		(16 "In7.Cu" signal "L8VCC")
		(18 "In8.Cu" signal "L9GND")
		(20 "In9.Cu" signal "L10")
		(22 "In10.Cu" signal "L11GND")
		(24 "In11.Cu" signal "L12")
		(26 "In12.Cu" signal "L13GND")
		(2 "B.Cu" signal "BOTTOM")
		(9 "F.Adhes" user "F.Adhesive")
		(11 "B.Adhes" user "B.Adhesive")
		(13 "F.Paste" user "Package Geometry/Pastemask Top")
		(15 "B.Paste" user "Package Geometry/Pastemask Bottom")
		(5 "F.SilkS" user "Ref Des/Silkscreen Top")
		(7 "B.SilkS" user "Ref Des/Silkscreen Bottom")
		(1 "F.Mask" user "Board Geometry/Soldermask Top")
		(3 "B.Mask" user "Board Geometry/Soldermask Bottom")
		(17 "Dwgs.User" user "User.Drawings")
		(19 "Cmts.User" user "User.Comments")
		(21 "Eco1.User" user "User.Eco1")
		(23 "Eco2.User" user "User.Eco2")
		(25 "Edge.Cuts" user "Board Geometry/Outline")
		(27 "Margin" user)
		(31 "F.CrtYd" user "Package Geometry/Place Bound Top")
		(29 "B.CrtYd" user "Package Geometry/Place Bound Bottom")
		(35 "F.Fab" user "Ref Des/Assembly Top")
		(33 "B.Fab" user "Ref Des/Assembly Bottom")
	)
	(footprint ""
		(layer "B.Cu")
		(at 440.284362 -32.184848 180)
		(property "Reference" "C1W20"
			(at 0.8382 -0.67818 180)
			(unlocked yes)
			(layer "B.SilkS")
			(effects
				(font
					(size 0.4064 0.254)
					(thickness 0.1524)
				)
				(justify left mirror)
			)
		)
		(property "Value" ""
			(at 0 0 0)
			(layer "B.Fab")
			(effects
				(font
					(size 1.27 1.27)
				)
				(justify mirror)
			)
		)
		(duplicate_pad_numbers_are_jumpers no)
		(fp_poly
			(pts
				(xy -0.3048 -0.1016) (xy -0.3048 0.9906) (xy 0.3048 0.9906) (xy 0.3048 -0.1016)
			)
			(stroke
				(width 0)
				(type default)
			)
			(fill no)
			(layer "B.CrtYd")
		)
		(fp_line
			(start 0.3048 0.9906)
			(end -0.3048 0.9906)
			(stroke
				(width 0.1)
				(type default)
			)
			(layer "B.Fab")
		)
		(fp_line
			(start 0.3048 -0.1016)
			(end 0.3048 0.9906)
			(stroke
				(width 0.1)
				(type default)
			)
			(layer "B.Fab")
		)
		(fp_line
			(start -0.3048 0.9906)
			(end -0.3048 -0.1016)
			(stroke
				(width 0.1)
				(type default)
			)
			(layer "B.Fab")
		)
		(fp_line
			(start -0.3048 -0.1016)
			(end 0.3048 -0.1016)
			(stroke
				(width 0.1)
				(type default)
			)
			(layer "B.Fab")
		)
		(pad "1" smd rect
			(at 0 0)
			(size 0.508 0.508)
			(layers "B.Cu" "B.Mask" "B.Paste")
			(net "BMC_M_CLK")
		)
		(pad "2" smd rect
			(at 0 0.889)
			(size 0.508 0.508)
			(layers "B.Cu" "B.Mask" "B.Paste")
			(net "GND")
		)
		(zone
			(layer "B.Cu")
			(hatch none 0.5)
			(connect_pads
				(clearance 0)
			)
			(min_thickness 0.25)
			(keepout
				(tracks not_allowed)
				(vias allowed)
				(pads allowed)
				(copperpour not_allowed)
				(footprints allowed)
			)
			(placement
				(enabled no)
				(sheetname "")
			)
			(fill
				(thermal_gap 0.5)
				(thermal_bridge_width 0.5)
				(island_removal_mode 0)
			)
			(polygon
				(pts
					(xy 440.030362 -32.819848) (xy 440.538362 -32.819848) (xy 440.538362 -32.438848) (xy 440.030362 -32.438848)
				)
			)
		)
		(zone
			(layer "B.Cu")
			(hatch none 0.5)
			(connect_pads
				(clearance 0)
			)
			(min_thickness 0.25)
			(keepout
				(tracks allowed)
				(vias not_allowed)
				(pads allowed)
				(copperpour not_allowed)
				(footprints allowed)
			)
			(placement
				(enabled no)
				(sheetname "")
			)
			(fill
				(thermal_gap 0.5)
				(thermal_bridge_width 0.5)
				(island_removal_mode 0)
			)
			(polygon
				(pts
					(xy 440.030362 -32.438848) (xy 440.538362 -32.438848) (xy 440.538362 -32.819848) (xy 440.030362 -32.819848)
				)
			)
		)
	)
	(footprint ""
		(layer "B.Cu")
		(at 443.405006 -43.54195 180)
		(property "Reference" "R25W42"
			(at 0 0 0)
			(layer "B.SilkS")
			(hide yes)
			(effects
				(font
					(size 1.27 1.27)
				)
				(justify mirror)
			)
		)
		(property "Value" "*"
			(at -0.064008 -4.108196 180)
			(unlocked yes)
			(layer "B.Fab")
			(hide yes)
			(effects
				(font
					(size 1.27 1.016)
					(thickness 0.1524)
				)
				(justify mirror)
			)
		)
		(property "Device Type" "120R2F-GP_RCL_GP-120R2F-GP,64.A"
			(at -0.064008 -5.632196 180)
			(unlocked yes)
			(layer "B.Fab")
			(hide yes)
			(effects
				(font
					(size 1.27 1.016)
					(thickness 0.1524)
				)
				(justify mirror)
			)
		)
		(duplicate_pad_numbers_are_jumpers no)
		(fp_line
			(start 0.508 -0.9398)
			(end 0.508 0.9398)
			(stroke
				(width 0.1524)
				(type default)
			)
			(layer "B.SilkS")
		)
		(fp_line
			(start -0.508 -0.9398)
			(end 0.508 -0.9398)
			(stroke
				(width 0.1524)
				(type default)
			)
			(layer "B.SilkS")
		)
		(fp_rect
			(start 0.508 0.9398)
			(end -0.508 -0.9398)
			(stroke
				(width 0)
				(type default)
			)
			(fill no)
			(layer "B.CrtYd")
		)
		(fp_rect
			(start 0.508 0.9398)
			(end -0.508 -0.9398)
			(stroke
				(width 0)
				(type default)
			)
			(fill no)
			(layer "B.Fab")
		)
		(pad "1" smd custom
			(at 0 -0.4445)
			(size 0.1397 0.1397)
			(layers "B.Cu" "B.Mask" "B.Paste")
			(net "BMC_M_A4")
			(options
				(clearance outline)
				(anchor circle)
			)
			(primitives
				(gr_poly
					(pts
						(arc
							(start -0.1778 0.2794)
							(mid -0.249642 0.249642)
							(end -0.2794 0.1778)
						)
						(arc
							(start -0.2794 -0.1778)
							(mid -0.249642 -0.249642)
							(end -0.1778 -0.2794)
						)
						(arc
							(start 0.1778 -0.2794)
							(mid 0.249642 -0.249642)
							(end 0.2794 -0.1778)
						)
						(arc
							(start 0.2794 0.1778)
							(mid 0.249642 0.249642)
							(end 0.1778 0.2794)
						)
					)
					(width 0)
					(fill yes)
				)
			)
		)
		(pad "2" smd custom
			(at 0 0.4445)
			(size 0.1397 0.1397)
			(layers "B.Cu" "B.Mask" "B.Paste")
			(net "P1V2_AUX_BMC")
			(options
				(clearance outline)
				(anchor circle)
			)
			(primitives
				(gr_poly
					(pts
						(arc
							(start -0.1778 0.2794)
							(mid -0.249642 0.249642)
							(end -0.2794 0.1778)
						)
						(arc
							(start -0.2794 -0.1778)
							(mid -0.249642 -0.249642)
							(end -0.1778 -0.2794)
						)
						(arc
							(start 0.1778 -0.2794)
							(mid 0.249642 -0.249642)
							(end 0.2794 -0.1778)
						)
						(arc
							(start 0.2794 0.1778)
							(mid 0.249642 0.249642)
							(end 0.1778 0.2794)
						)
					)
					(width 0)
					(fill yes)
				)
			)
		)
	)
	(footprint ""
		(layer "B.Cu")
		(at 348.5134 -150.387304 -90)
		(property "Reference" "C3L13"
			(at 0 0 90)
			(layer "B.SilkS")
			(hide yes)
			(effects
				(font
					(size 1.27 1.27)
				)
				(justify mirror)
			)
		)
		(property "Value" ""
			(at 0 0 90)
			(layer "B.Fab")
			(effects
				(font
					(size 1.27 1.27)
				)
				(justify mirror)
			)
		)
		(duplicate_pad_numbers_are_jumpers no)
		(fp_poly
			(pts
				(xy 0.7239 -0.2159) (xy -0.7239 -0.2159) (xy -0.7239 1.9939) (xy 0.7239 1.9939)
			)
			(stroke
				(width 0)
				(type default)
			)
			(fill no)
			(layer "B.CrtYd")
		)
		(fp_line
			(start -0.7239 1.9939)
			(end -0.7239 -0.2159)
			(stroke
				(width 0.1)
				(type default)
			)
			(layer "B.Fab")
		)
		(fp_line
			(start 0.7239 1.9939)
			(end -0.7239 1.9939)
			(stroke
				(width 0.1)
				(type default)
			)
			(layer "B.Fab")
		)
		(fp_line
			(start -0.7239 -0.2159)
			(end 0.7239 -0.2159)
			(stroke
				(width 0.1)
				(type default)
			)
			(layer "B.Fab")
		)
		(fp_line
			(start 0.7239 -0.2159)
			(end 0.7239 1.9939)
			(stroke
				(width 0.1)
				(type default)
			)
			(layer "B.Fab")
		)
		(pad "1" smd rect
			(at 0 0 90)
			(size 1.27 1.016)
			(layers "B.Cu" "B.Mask" "B.Paste")
			(net "VR_FET_SW_P12V_STBY_PVDDQ_DEF")
		)
		(pad "2" smd rect
			(at 0 1.778 90)
			(size 1.27 1.016)
			(layers "B.Cu" "B.Mask" "B.Paste")
			(net "GND")
		)
		(zone
			(layer "B.Cu")
			(hatch none 0.5)
			(connect_pads
				(clearance 0)
			)
			(min_thickness 0.25)
			(keepout
				(tracks not_allowed)
				(vias allowed)
				(pads allowed)
				(copperpour not_allowed)
				(footprints allowed)
			)
			(placement
				(enabled no)
				(sheetname "")
			)
			(fill
				(thermal_gap 0.5)
				(thermal_bridge_width 0.5)
				(island_removal_mode 0)
			)
			(polygon
				(pts
					(xy 348.0054 -149.752304) (xy 348.0054 -151.022304) (xy 347.2434 -151.022304) (xy 347.2434 -149.752304)
				)
			)
		)
	)
)
